(kicad_pcb
	(version 20241229)
	(generator "pcbnew")
	(generator_version "9.0")
	(general
		(thickness 1.711)
		(legacy_teardrops no)
	)
	(paper "A4")
	(title_block
		(title "Antmicro Baseboard for Jetson AGX Thor")
		(date "2026-02-18")
		(rev "1.1.0")
		(company "Antmicro Ltd")
		(comment 1 "www.antmicro.com")
		(comment 9 "footprint 425 of 1170 (U21), pads 1-69 of 101")
	)
	(layers
		(0 "F.Cu" signal)
		(4 "In1.Cu" signal)
		(6 "In2.Cu" signal)
		(8 "In3.Cu" signal)
		(10 "In4.Cu" jumper)
		(12 "In5.Cu" signal)
		(14 "In6.Cu" signal)
		(16 "In7.Cu" signal)
		(18 "In8.Cu" signal)
		(2 "B.Cu" signal)
		(9 "F.Adhes" user "F.Adhesive")
		(11 "B.Adhes" user "B.Adhesive")
		(13 "F.Paste" user)
		(15 "B.Paste" user)
		(5 "F.SilkS" user "F.Silkscreen")
		(7 "B.SilkS" user "B.Silkscreen")
		(1 "F.Mask" user)
		(3 "B.Mask" user)
		(17 "Dwgs.User" user "User.Drawings")
		(19 "Cmts.User" user "User.Comments")
		(21 "Eco1.User" user "User.Eco1")
		(23 "Eco2.User" user "User.Eco2")
		(25 "Edge.Cuts" user)
		(27 "Margin" user)
		(31 "F.CrtYd" user "F.Courtyard")
		(29 "B.CrtYd" user "B.Courtyard")
		(35 "F.Fab" user)
		(33 "B.Fab" user)
	)
	(footprint "antmicro-footprints:VQFN-100-1EP_12x12x0.85mm_P0.4mm"
		(layer "F.Cu")
		(at 205.353 125.699 180)
		(property "Reference" "U21"
			(at 6.653 6.699 180)
			(layer "F.SilkS")
			(effects
				(font
					(size 0.7 0.7)
					(thickness 0.15)
				)
				(justify left bottom)
			)
		)
		(property "Value" "USB7252C"
			(at 0 7.6 0)
			(layer "F.Fab")
			(effects
				(font
					(size 0.7 0.7)
					(thickness 0.15)
				)
				(justify right top)
			)
		)
		(property "Datasheet" "https://ww1.microchip.com/downloads/en/DeviceDoc/00003852A.pdf"
			(at 0 0 0)
			(layer "F.Fab")
			(hide yes)
			(effects
				(font
					(size 1.27 1.27)
					(thickness 0.15)
				)
			)
		)
		(property "Description" "4-Port USB 3.2 Hub, 2x Type-C with Power Delivery support, 1x USB 3.2, 1x USB 2.0"
			(at 0 0 0)
			(layer "F.Fab")
			(hide yes)
			(effects
				(font
					(size 1.27 1.27)
					(thickness 0.15)
				)
			)
		)
		(property "MPN" "USB7252CT-I/KDX "
			(at 0 0 180)
			(unlocked yes)
			(layer "F.Fab")
			(hide yes)
			(effects
				(font
					(size 1 1)
					(thickness 0.15)
				)
			)
		)
		(property "Manufacturer" "Microchip Technology"
			(at 0 0 180)
			(unlocked yes)
			(layer "F.Fab")
			(hide yes)
			(effects
				(font
					(size 1 1)
					(thickness 0.15)
				)
			)
		)
		(property "Author" "Antmicro"
			(at 0 0 180)
			(unlocked yes)
			(layer "F.Fab")
			(hide yes)
			(effects
				(font
					(size 1 1)
					(thickness 0.15)
				)
			)
		)
		(property "License" "Apache-2.0"
			(at 0 0 180)
			(unlocked yes)
			(layer "F.Fab")
			(hide yes)
			(effects
				(font
					(size 1 1)
					(thickness 0.15)
				)
			)
		)
		(sheetname "/USB Hub/")
		(sheetfile "usb_hub.kicad_sch")
		(attr smd)
		(pad "1" smd roundrect
			(at -5.789 -4.802 270)
			(size 0.204 1.011199)
			(layers "F.Cu" "F.Mask" "F.Paste")
			(roundrect_rratio 0.25)
			(net 527 "/USB Hub/~{RESET}")
			(pinfunction "RESET_N")
			(pintype "input")
		)
		(pad "2" smd roundrect
			(at -5.789 -4.401 270)
			(size 0.204 1.011199)
			(layers "F.Cu" "F.Mask" "F.Paste")
			(roundrect_rratio 0.25)
			(net 1094 "unconnected-(U21-PF30-Pad2)")
			(pinfunction "PF30")
			(pintype "bidirectional+no_connect")
		)
		(pad "3" smd roundrect
			(at -5.789 -4 270)
			(size 0.204 1.011199)
			(layers "F.Cu" "F.Mask" "F.Paste")
			(roundrect_rratio 0.25)
			(net 1090 "unconnected-(U21-PF31-Pad3)")
			(pinfunction "PF31")
			(pintype "bidirectional+no_connect")
		)
		(pad "4" smd roundrect
			(at -5.789 -3.601 270)
			(size 0.204 1.011199)
			(layers "F.Cu" "F.Mask" "F.Paste")
			(roundrect_rratio 0.25)
			(net 932 "/USB Hub/USBC4_VBUS_MON")
			(pinfunction "DP1_VBUS_MON")
			(pintype "bidirectional")
		)
		(pad "5" smd roundrect
			(at -5.789 -3.201 270)
			(size 0.204 1.011199)
			(layers "F.Cu" "F.Mask" "F.Paste")
			(roundrect_rratio 0.25)
			(net 505 "/USB Hub/USBC4_D+")
			(pinfunction "USB2DN_DP1")
			(pintype "bidirectional")
		)
		(pad "6" smd roundrect
			(at -5.789 -2.801 270)
			(size 0.204 1.011199)
			(layers "F.Cu" "F.Mask" "F.Paste")
			(roundrect_rratio 0.25)
			(net 499 "/USB Hub/USBC4_D-")
			(pinfunction "USB2DN_DM1")
			(pintype "bidirectional")
		)
		(pad "7" smd roundrect
			(at -5.789 -2.4 270)
			(size 0.204 1.011199)
			(layers "F.Cu" "F.Mask" "F.Paste")
			(roundrect_rratio 0.25)
			(net 40 "/USB Hub/USBC4_TX_{1}+")
			(pinfunction "USB3DN_TXDP1A")
			(pintype "bidirectional")
		)
		(pad "8" smd roundrect
			(at -5.789 -2.001 270)
			(size 0.204 1.011199)
			(layers "F.Cu" "F.Mask" "F.Paste")
			(roundrect_rratio 0.25)
			(net 44 "/USB Hub/USBC4_TX_{1}-")
			(pinfunction "USB3DN_TXDM1A")
			(pintype "bidirectional")
		)
		(pad "9" smd roundrect
			(at -5.789 -1.601 270)
			(size 0.204 1.011199)
			(layers "F.Cu" "F.Mask" "F.Paste")
			(roundrect_rratio 0.25)
			(net 282 "+1V15")
			(pinfunction "VCORE")
			(pintype "power_in")
		)
		(pad "10" smd roundrect
			(at -5.789 -1.2 270)
			(size 0.204 1.011199)
			(layers "F.Cu" "F.Mask" "F.Paste")
			(roundrect_rratio 0.25)
			(net 504 "/USB Hub/USBC4_RX_{1}+")
			(pinfunction "USB3DN_RXDP1A")
			(pintype "bidirectional")
		)
		(pad "11" smd roundrect
			(at -5.789 -0.802 270)
			(size 0.204 1.011199)
			(layers "F.Cu" "F.Mask" "F.Paste")
			(roundrect_rratio 0.25)
			(net 501 "/USB Hub/USBC4_RX_{1}-")
			(pinfunction "USB3DN_RXDM1A")
			(pintype "bidirectional")
		)
		(pad "12" smd roundrect
			(at -5.789 -0.401 270)
			(size 0.204 1.011199)
			(layers "F.Cu" "F.Mask" "F.Paste")
			(roundrect_rratio 0.25)
			(net 503 "/USB Hub/USBC4_CC_{1}")
			(pinfunction "DP1_CC1")
			(pintype "bidirectional")
		)
		(pad "13" smd roundrect
			(at -5.789 0 270)
			(size 0.204 1.011199)
			(layers "F.Cu" "F.Mask" "F.Paste")
			(roundrect_rratio 0.25)
			(net 502 "/USB Hub/USBC4_CC_{2}")
			(pinfunction "DP1_CC2")
			(pintype "bidirectional")
		)
		(pad "14" smd roundrect
			(at -5.789 0.399 270)
			(size 0.204 1.011199)
			(layers "F.Cu" "F.Mask" "F.Paste")
			(roundrect_rratio 0.25)
			(net 1138 "Net-(U21-USB2DN_DP4)")
			(pinfunction "USB2DN_DP4")
			(pintype "bidirectional")
		)
		(pad "15" smd roundrect
			(at -5.789 0.8 270)
			(size 0.204 1.011199)
			(layers "F.Cu" "F.Mask" "F.Paste")
			(roundrect_rratio 0.25)
			(net 1141 "Net-(U21-USB2DN_DM4)")
			(pinfunction "USB2DN_DM4")
			(pintype "bidirectional")
		)
		(pad "16" smd roundrect
			(at -5.789 1.199 270)
			(size 0.204 1.011199)
			(layers "F.Cu" "F.Mask" "F.Paste")
			(roundrect_rratio 0.25)
			(net 41 "/USB Hub/USBC4_TX_{2}+")
			(pinfunction "USB3DN_TXDP1B")
			(pintype "bidirectional")
		)
		(pad "17" smd roundrect
			(at -5.789 1.598 270)
			(size 0.204 1.011199)
			(layers "F.Cu" "F.Mask" "F.Paste")
			(roundrect_rratio 0.25)
			(net 214 "/USB Hub/USBC4_TX_{2}-")
			(pinfunction "USB3DN_TXDM1B")
			(pintype "bidirectional")
		)
		(pad "18" smd roundrect
			(at -5.789 1.999 270)
			(size 0.204 1.011199)
			(layers "F.Cu" "F.Mask" "F.Paste")
			(roundrect_rratio 0.25)
			(net 282 "+1V15")
			(pinfunction "VCORE")
			(pintype "power_in")
		)
		(pad "19" smd roundrect
			(at -5.789 2.398 270)
			(size 0.204 1.011199)
			(layers "F.Cu" "F.Mask" "F.Paste")
			(roundrect_rratio 0.25)
			(net 498 "/USB Hub/USBC4_RX_{2}+")
			(pinfunction "USB3DN_RXDP1B")
			(pintype "bidirectional")
		)
		(pad "20" smd roundrect
			(at -5.789 2.798 270)
			(size 0.204 1.011199)
			(layers "F.Cu" "F.Mask" "F.Paste")
			(roundrect_rratio 0.25)
			(net 500 "/USB Hub/USBC4_RX_{2}-")
			(pinfunction "USB3DN_RXDM1B")
			(pintype "bidirectional")
		)
		(pad "21" smd roundrect
			(at -5.789 3.199 270)
			(size 0.204 1.011199)
			(layers "F.Cu" "F.Mask" "F.Paste")
			(roundrect_rratio 0.25)
			(net 913 "/USB Hub/CFG_STRAP1")
			(pinfunction "CFG_STRAP1")
			(pintype "input")
		)
		(pad "22" smd roundrect
			(at -5.789 3.6 270)
			(size 0.204 1.011199)
			(layers "F.Cu" "F.Mask" "F.Paste")
			(roundrect_rratio 0.25)
			(net 915 "/USB Hub/CFG_STRAP2")
			(pinfunction "CFG_STRAP2")
			(pintype "input")
		)
		(pad "23" smd roundrect
			(at -5.789 3.999 270)
			(size 0.204 1.011199)
			(layers "F.Cu" "F.Mask" "F.Paste")
			(roundrect_rratio 0.25)
			(net 931 "/USB Hub/CFG_STRAP3")
			(pinfunction "CFG_STRAP3")
			(pintype "input")
		)
		(pad "24" smd roundrect
			(at -5.789 4.398 270)
			(size 0.204 1.011199)
			(layers "F.Cu" "F.Mask" "F.Paste")
			(roundrect_rratio 0.25)
			(net 1 "GND")
			(pinfunction "TESTEN")
			(pintype "bidirectional")
		)
		(pad "25" smd roundrect
			(at -5.789 4.799 270)
			(size 0.204 1.011199)
			(layers "F.Cu" "F.Mask" "F.Paste")
			(roundrect_rratio 0.25)
			(net 282 "+1V15")
			(pinfunction "VCORE")
			(pintype "power_in")
		)
		(pad "26" smd roundrect
			(at -4.802 5.788 180)
			(size 0.204 1.011199)
			(layers "F.Cu" "F.Mask" "F.Paste")
			(roundrect_rratio 0.25)
			(net 2 "+3V3")
			(pinfunction "VDD33")
			(pintype "power_in")
		)
		(pad "27" smd roundrect
			(at -4.401 5.788 180)
			(size 0.204 1.011199)
			(layers "F.Cu" "F.Mask" "F.Paste")
			(roundrect_rratio 0.25)
			(net 510 "/USB Hub/USBC3_CC_{1}")
			(pinfunction "DP2_CC1")
			(pintype "bidirectional")
		)
		(pad "28" smd roundrect
			(at -4 5.788 180)
			(size 0.204 1.011199)
			(layers "F.Cu" "F.Mask" "F.Paste")
			(roundrect_rratio 0.25)
			(net 509 "/USB Hub/USBC3_CC_{2}")
			(pinfunction "DP2_CC2")
			(pintype "bidirectional")
		)
		(pad "29" smd roundrect
			(at -3.601 5.788 180)
			(size 0.204 1.011199)
			(layers "F.Cu" "F.Mask" "F.Paste")
			(roundrect_rratio 0.25)
			(net 506 "/USB Hub/USBC3_D+")
			(pinfunction "USB2DN_DP2")
			(pintype "bidirectional")
		)
		(pad "30" smd roundrect
			(at -3.201 5.788 180)
			(size 0.204 1.011199)
			(layers "F.Cu" "F.Mask" "F.Paste")
			(roundrect_rratio 0.25)
			(net 508 "/USB Hub/USBC3_D-")
			(pinfunction "USB2DN_DM2")
			(pintype "bidirectional")
		)
		(pad "31" smd roundrect
			(at -2.801 5.788 180)
			(size 0.204 1.011199)
			(layers "F.Cu" "F.Mask" "F.Paste")
			(roundrect_rratio 0.25)
			(net 45 "/USB Hub/USBC3_TX_{1}+")
			(pinfunction "USB3DN_TXDP2A")
			(pintype "bidirectional")
		)
		(pad "32" smd roundrect
			(at -2.4 5.788 180)
			(size 0.204 1.011199)
			(layers "F.Cu" "F.Mask" "F.Paste")
			(roundrect_rratio 0.25)
			(net 283 "/USB Hub/USBC3_TX_{1}-")
			(pinfunction "USB3DN_TXDM2A")
			(pintype "bidirectional")
		)
		(pad "33" smd roundrect
			(at -2.001 5.788 180)
			(size 0.204 1.011199)
			(layers "F.Cu" "F.Mask" "F.Paste")
			(roundrect_rratio 0.25)
			(net 282 "+1V15")
			(pinfunction "VCORE")
			(pintype "power_in")
		)
		(pad "34" smd roundrect
			(at -1.601 5.788 180)
			(size 0.204 1.011199)
			(layers "F.Cu" "F.Mask" "F.Paste")
			(roundrect_rratio 0.25)
			(net 513 "/USB Hub/USBC3_RX_{1}+")
			(pinfunction "USB3DN_RXDP2A")
			(pintype "bidirectional")
		)
		(pad "35" smd roundrect
			(at -1.2 5.788 180)
			(size 0.204 1.011199)
			(layers "F.Cu" "F.Mask" "F.Paste")
			(roundrect_rratio 0.25)
			(net 507 "/USB Hub/USBC3_RX_{1}-")
			(pinfunction "USB3DN_RXDM2A")
			(pintype "bidirectional")
		)
		(pad "36" smd roundrect
			(at -0.802 5.788 180)
			(size 0.204 1.011199)
			(layers "F.Cu" "F.Mask" "F.Paste")
			(roundrect_rratio 0.25)
			(net 1016 "/USB Hub/USBC3_VBUS_MON")
			(pinfunction "DP2_VBUS_MON")
			(pintype "bidirectional")
		)
		(pad "37" smd roundrect
			(at -0.401 5.788 180)
			(size 0.204 1.011199)
			(layers "F.Cu" "F.Mask" "F.Paste")
			(roundrect_rratio 0.25)
			(net 212 "/USB Hub/USBC3_TX_{2}+")
			(pinfunction "USB3DN_TXDP2B")
			(pintype "bidirectional")
		)
		(pad "38" smd roundrect
			(at 0 5.788 180)
			(size 0.204 1.011199)
			(layers "F.Cu" "F.Mask" "F.Paste")
			(roundrect_rratio 0.25)
			(net 285 "/USB Hub/USBC3_TX_{2}-")
			(pinfunction "USB3DN_TXDM2B")
			(pintype "bidirectional")
		)
		(pad "39" smd roundrect
			(at 0.399 5.788 180)
			(size 0.204 1.011199)
			(layers "F.Cu" "F.Mask" "F.Paste")
			(roundrect_rratio 0.25)
			(net 282 "+1V15")
			(pinfunction "VCORE")
			(pintype "power_in")
		)
		(pad "40" smd roundrect
			(at 0.8 5.788 180)
			(size 0.204 1.011199)
			(layers "F.Cu" "F.Mask" "F.Paste")
			(roundrect_rratio 0.25)
			(net 512 "/USB Hub/USBC3_RX_{2}+")
			(pinfunction "USB3DN_RXDP2B")
			(pintype "bidirectional")
		)
		(pad "41" smd roundrect
			(at 1.199 5.788 180)
			(size 0.204 1.011199)
			(layers "F.Cu" "F.Mask" "F.Paste")
			(roundrect_rratio 0.25)
			(net 511 "/USB Hub/USBC3_RX_{2}-")
			(pinfunction "USB3DN_RXDM2B")
			(pintype "bidirectional")
		)
		(pad "42" smd roundrect
			(at 1.598 5.788 180)
			(size 0.204 1.011199)
			(layers "F.Cu" "F.Mask" "F.Paste")
			(roundrect_rratio 0.25)
			(net 2 "+3V3")
			(pinfunction "VDD33")
			(pintype "power_in")
		)
		(pad "43" smd roundrect
			(at 1.999 5.788 180)
			(size 0.204 1.011199)
			(layers "F.Cu" "F.Mask" "F.Paste")
			(roundrect_rratio 0.25)
			(net 1084 "/USB Hub/DP1_VCONN1")
			(pinfunction "PF2")
			(pintype "bidirectional")
		)
		(pad "44" smd roundrect
			(at 2.398 5.788 180)
			(size 0.204 1.011199)
			(layers "F.Cu" "F.Mask" "F.Paste")
			(roundrect_rratio 0.25)
			(net 1095 "/USB Hub/DP1_VCONN2")
			(pinfunction "PF3")
			(pintype "bidirectional")
		)
		(pad "45" smd roundrect
			(at 2.798 5.788 180)
			(size 0.204 1.011199)
			(layers "F.Cu" "F.Mask" "F.Paste")
			(roundrect_rratio 0.25)
			(net 1085 "/USB Hub/DP2_DISCH")
			(pinfunction "PF4")
			(pintype "bidirectional")
		)
		(pad "46" smd roundrect
			(at 3.199 5.788 180)
			(size 0.204 1.011199)
			(layers "F.Cu" "F.Mask" "F.Paste")
			(roundrect_rratio 0.25)
			(net 1103 "/USB Hub/DP1_DISCH")
			(pinfunction "PF5")
			(pintype "bidirectional")
		)
		(pad "47" smd roundrect
			(at 3.6 5.788 180)
			(size 0.204 1.011199)
			(layers "F.Cu" "F.Mask" "F.Paste")
			(roundrect_rratio 0.25)
			(net 1097 "unconnected-(U21-PF6-Pad47)")
			(pinfunction "PF6")
			(pintype "bidirectional+no_connect")
		)
		(pad "48" smd roundrect
			(at 3.999 5.788 180)
			(size 0.204 1.011199)
			(layers "F.Cu" "F.Mask" "F.Paste")
			(roundrect_rratio 0.25)
			(net 1082 "unconnected-(U21-PF7-Pad48)")
			(pinfunction "PF7")
			(pintype "bidirectional+no_connect")
		)
		(pad "49" smd roundrect
			(at 4.398 5.788 180)
			(size 0.204 1.011199)
			(layers "F.Cu" "F.Mask" "F.Paste")
			(roundrect_rratio 0.25)
			(net 1098 "unconnected-(U21-PF8-Pad49)")
			(pinfunction "PF8")
			(pintype "bidirectional+no_connect")
		)
		(pad "50" smd roundrect
			(at 4.799 5.788 180)
			(size 0.204 1.011199)
			(layers "F.Cu" "F.Mask" "F.Paste")
			(roundrect_rratio 0.25)
			(net 1092 "unconnected-(U21-PF9-Pad50)")
			(pinfunction "PF9")
			(pintype "bidirectional+no_connect")
		)
		(pad "51" smd roundrect
			(at 5.788 4.799 270)
			(size 0.204 1.011199)
			(layers "F.Cu" "F.Mask" "F.Paste")
			(roundrect_rratio 0.25)
			(net 1099 "/USB Hub/DP2_VCONN1")
			(pinfunction "PF10")
			(pintype "bidirectional")
		)
		(pad "52" smd roundrect
			(at 5.788 4.398 270)
			(size 0.204 1.011199)
			(layers "F.Cu" "F.Mask" "F.Paste")
			(roundrect_rratio 0.25)
			(net 1106 "/USB Hub/DP2_VCONN2")
			(pinfunction "PF11")
			(pintype "bidirectional")
		)
		(pad "53" smd roundrect
			(at 5.788 3.999 270)
			(size 0.204 1.011199)
			(layers "F.Cu" "F.Mask" "F.Paste")
			(roundrect_rratio 0.25)
			(net 2 "+3V3")
			(pinfunction "VDD33")
			(pintype "power_in")
		)
		(pad "54" smd roundrect
			(at 5.788 3.6 270)
			(size 0.204 1.011199)
			(layers "F.Cu" "F.Mask" "F.Paste")
			(roundrect_rratio 0.25)
			(net 1175 "unconnected-(U21-PF12-Pad54)")
			(pinfunction "PF12")
			(pintype "bidirectional+no_connect")
		)
		(pad "55" smd roundrect
			(at 5.788 3.199 270)
			(size 0.204 1.011199)
			(layers "F.Cu" "F.Mask" "F.Paste")
			(roundrect_rratio 0.25)
			(net 282 "+1V15")
			(pinfunction "VCORE")
			(pintype "power_in")
		)
		(pad "56" smd roundrect
			(at 5.788 2.798 270)
			(size 0.204 1.011199)
			(layers "F.Cu" "F.Mask" "F.Paste")
			(roundrect_rratio 0.25)
			(net 910 "/USB Hub/PRT_CTL3")
			(pinfunction "PF13")
			(pintype "bidirectional")
		)
		(pad "57" smd roundrect
			(at 5.788 2.398 270)
			(size 0.204 1.011199)
			(layers "F.Cu" "F.Mask" "F.Paste")
			(roundrect_rratio 0.25)
			(net 1173 "unconnected-(U21-PF14-Pad57)")
			(pinfunction "PF14")
			(pintype "bidirectional+no_connect")
		)
		(pad "58" smd roundrect
			(at 5.788 1.999 270)
			(size 0.204 1.011199)
			(layers "F.Cu" "F.Mask" "F.Paste")
			(roundrect_rratio 0.25)
			(net 911 "/USB Hub/PRT_CTL2")
			(pinfunction "PF15")
			(pintype "bidirectional")
		)
		(pad "59" smd roundrect
			(at 5.788 1.598 270)
			(size 0.204 1.011199)
			(layers "F.Cu" "F.Mask" "F.Paste")
			(roundrect_rratio 0.25)
			(net 912 "/USB Hub/PRT_CTL4")
			(pinfunction "PF16")
			(pintype "bidirectional")
		)
		(pad "60" smd roundrect
			(at 5.788 1.199 270)
			(size 0.204 1.011199)
			(layers "F.Cu" "F.Mask" "F.Paste")
			(roundrect_rratio 0.25)
			(net 914 "/USB Hub/PRT_CTL1")
			(pinfunction "PF17")
			(pintype "bidirectional")
		)
		(pad "61" smd roundrect
			(at 5.788 0.8 270)
			(size 0.204 1.011199)
			(layers "F.Cu" "F.Mask" "F.Paste")
			(roundrect_rratio 0.25)
			(net 1174 "unconnected-(U21-PF18-Pad61)")
			(pinfunction "PF18")
			(pintype "bidirectional+no_connect")
		)
		(pad "62" smd roundrect
			(at 5.788 0.399 270)
			(size 0.204 1.011199)
			(layers "F.Cu" "F.Mask" "F.Paste")
			(roundrect_rratio 0.25)
			(net 2 "+3V3")
			(pinfunction "VDD33")
			(pintype "power_in")
		)
		(pad "63" smd roundrect
			(at 5.788 0 270)
			(size 0.204 1.011199)
			(layers "F.Cu" "F.Mask" "F.Paste")
			(roundrect_rratio 0.25)
			(net 920 "/USB Hub/TEST1")
			(pinfunction "TEST1")
			(pintype "passive")
		)
		(pad "64" smd roundrect
			(at 5.788 -0.401 270)
			(size 0.204 1.011199)
			(layers "F.Cu" "F.Mask" "F.Paste")
			(roundrect_rratio 0.25)
			(net 917 "/USB Hub/TEST2")
			(pinfunction "TEST2")
			(pintype "passive")
		)
		(pad "65" smd roundrect
			(at 5.788 -0.802 270)
			(size 0.204 1.011199)
			(layers "F.Cu" "F.Mask" "F.Paste")
			(roundrect_rratio 0.25)
			(net 916 "/USB Hub/TEST3")
			(pinfunction "TEST3")
			(pintype "passive")
		)
		(pad "66" smd roundrect
			(at 5.788 -1.2 270)
			(size 0.204 1.011199)
			(layers "F.Cu" "F.Mask" "F.Paste")
			(roundrect_rratio 0.25)
			(net 1233 "Net-(U21-PF19)")
			(pinfunction "PF19")
			(pintype "bidirectional")
		)
		(pad "67" smd roundrect
			(at 5.788 -1.601 270)
			(size 0.204 1.011199)
			(layers "F.Cu" "F.Mask" "F.Paste")
			(roundrect_rratio 0.25)
			(net 2 "+3V3")
			(pinfunction "VDD33")
			(pintype "power_in")
		)
		(pad "68" smd roundrect
			(at 5.788 -2 270)
			(size 0.204 1.011199)
			(layers "F.Cu" "F.Mask" "F.Paste")
			(roundrect_rratio 0.25)
			(net 927 "/USB Hub/HUB_SPI_CLK")
			(pinfunction "SPI_CLK")
			(pintype "bidirectional")
		)
		(pad "69" smd roundrect
			(at 5.788 -2.4 270)
			(size 0.204 1.011199)
			(layers "F.Cu" "F.Mask" "F.Paste")
			(roundrect_rratio 0.25)
			(net 930 "/USB Hub/HUB_SPI_CE_N")
			(pinfunction "SPI_CE_N")
			(pintype "bidirectional")
		)
	)
)
